(kicad_pcb
	(version 20260206)
	(generator "pcbnew")
	(generator_version "10.0")
	(general
		(thickness 1.6)
		(legacy_teardrops no)
	)
	(paper "A4")
	(title_block
		(title "03242023_DA0F0TMBIJ0_F0T_Motherboard_J_brd_V01_OCP.brd")
		(comment 1 "Grand Teton / footprints 2390-2395 of 6105")
	)
	(layers
		(0 "F.Cu" signal "TOP")
		(4 "In1.Cu" signal "GND")
		(6 "In2.Cu" signal "IN1")
		(8 "In3.Cu" signal "GND1")
		(10 "In4.Cu" signal "IN2")
		(12 "In5.Cu" signal "GND2")
		(14 "In6.Cu" signal "IN3")
		(16 "In7.Cu" signal "GND3")
		(18 "In8.Cu" signal "VCC")
		(20 "In9.Cu" signal "VCC1")
		(22 "In10.Cu" signal "GND4")
		(24 "In11.Cu" signal "IN4")
		(26 "In12.Cu" signal "GND5")
		(28 "In13.Cu" signal "IN5")
		(30 "In14.Cu" signal "GND6")
		(32 "In15.Cu" signal "IN6")
		(34 "In16.Cu" signal "GND7")
		(2 "B.Cu" signal "BOTTOM")
		(9 "F.Adhes" user "F.Adhesive")
		(11 "B.Adhes" user "B.Adhesive")
		(13 "F.Paste" user "Package Geometry/Pastemask Top")
		(15 "B.Paste" user "Package Geometry/Pastemask Bottom")
		(5 "F.SilkS" user "Ref Des/Silkscreen Top")
		(7 "B.SilkS" user "Ref Des/Silkscreen Bottom")
		(1 "F.Mask" user "Board Geometry/Soldermask Top")
		(3 "B.Mask" user "Board Geometry/Soldermask Bottom")
		(17 "Dwgs.User" user "User.Drawings")
		(19 "Cmts.User" user "User.Comments")
		(21 "Eco1.User" user "User.Eco1")
		(23 "Eco2.User" user "User.Eco2")
		(25 "Edge.Cuts" user "Board Geometry/Outline")
		(27 "Margin" user)
		(31 "F.CrtYd" user "Package Geometry/Place Bound Top")
		(29 "B.CrtYd" user "Package Geometry/Place Bound Bottom")
		(35 "F.Fab" user "Ref Des/Assembly Top")
		(33 "B.Fab" user "Ref Des/Assembly Bottom")
	)
	(footprint ""
		(layer "F.Cu")
		(at 203.326492 -101.606604 -90)
		(property "Reference" "R1839"
			(at 0 0 270)
			(layer "F.SilkS")
			(hide yes)
			(effects
				(font
					(size 1.27 1.27)
				)
			)
		)
		(property "Value" ""
			(at 0 0 270)
			(layer "F.Fab")
			(effects
				(font
					(size 1.27 1.27)
				)
			)
		)
		(duplicate_pad_numbers_are_jumpers no)
		(fp_line
			(start -0.7874 0.4064)
			(end -0.7874 -0.4064)
			(stroke
				(width 0.1524)
				(type default)
			)
			(layer "F.SilkS")
		)
		(fp_line
			(start 0.7874 0.4064)
			(end -0.7874 0.4064)
			(stroke
				(width 0.1524)
				(type default)
			)
			(layer "F.SilkS")
		)
		(fp_line
			(start -0.7874 -0.4064)
			(end 0.7874 -0.4064)
			(stroke
				(width 0.1524)
				(type default)
			)
			(layer "F.SilkS")
		)
		(fp_line
			(start 0.7874 -0.4064)
			(end 0.7874 0.4064)
			(stroke
				(width 0.1524)
				(type default)
			)
			(layer "F.SilkS")
		)
		(fp_line
			(start -0.67945 0.3048)
			(end -0.67945 -0.305054)
			(stroke
				(width 0.1)
				(type default)
			)
			(layer "F.Fab")
		)
		(fp_line
			(start -0.12065 0.3048)
			(end -0.67945 0.3048)
			(stroke
				(width 0.1)
				(type default)
			)
			(layer "F.Fab")
		)
		(fp_line
			(start 0.120396 0.3048)
			(end 0.120396 0.2794)
			(stroke
				(width 0.1)
				(type default)
			)
			(layer "F.Fab")
		)
		(fp_line
			(start 0.67945 0.3048)
			(end 0.120396 0.3048)
			(stroke
				(width 0.1)
				(type default)
			)
			(layer "F.Fab")
		)
		(fp_line
			(start -0.12065 0.2794)
			(end -0.12065 0.3048)
			(stroke
				(width 0.1)
				(type default)
			)
			(layer "F.Fab")
		)
		(fp_line
			(start 0.120396 0.2794)
			(end -0.12065 0.2794)
			(stroke
				(width 0.1)
				(type default)
			)
			(layer "F.Fab")
		)
		(fp_line
			(start -0.12065 -0.2794)
			(end 0.12065 -0.2794)
			(stroke
				(width 0.1)
				(type default)
			)
			(layer "F.Fab")
		)
		(fp_line
			(start 0.12065 -0.2794)
			(end 0.12065 -0.3048)
			(stroke
				(width 0.1)
				(type default)
			)
			(layer "F.Fab")
		)
		(fp_line
			(start 0.12065 -0.3048)
			(end 0.67945 -0.3048)
			(stroke
				(width 0.1)
				(type default)
			)
			(layer "F.Fab")
		)
		(fp_line
			(start 0.67945 -0.3048)
			(end 0.67945 0.3048)
			(stroke
				(width 0.1)
				(type default)
			)
			(layer "F.Fab")
		)
		(fp_line
			(start -0.67945 -0.305054)
			(end -0.12065 -0.305054)
			(stroke
				(width 0.1)
				(type default)
			)
			(layer "F.Fab")
		)
		(fp_line
			(start -0.12065 -0.305054)
			(end -0.12065 -0.2794)
			(stroke
				(width 0.1)
				(type default)
			)
			(layer "F.Fab")
		)
		(pad "1" smd circle
			(at -0.40005 0 270)
			(size 0 0)
			(layers "F.Cu" "F.Mask" "F.Paste")
			(net "RST_PFR_OVR_RTC")
		)
		(pad "2" smd circle
			(at 0.40005 0 270)
			(size 0 0)
			(layers "F.Cu" "F.Mask" "F.Paste")
			(net "RST_RTCRST_N")
		)
	)
	(footprint ""
		(layer "F.Cu")
		(at 22.13356 -165.751256)
		(property "Reference" "R2578"
			(at 0 0 0)
			(layer "F.SilkS")
			(hide yes)
			(effects
				(font
					(size 1.27 1.27)
				)
			)
		)
		(property "Value" ""
			(at 0 0 0)
			(layer "F.Fab")
			(effects
				(font
					(size 1.27 1.27)
				)
			)
		)
		(duplicate_pad_numbers_are_jumpers no)
		(fp_line
			(start -0.7874 -0.4064)
			(end 0.7874 -0.4064)
			(stroke
				(width 0.1524)
				(type default)
			)
			(layer "F.SilkS")
		)
		(fp_line
			(start -0.7874 0.4064)
			(end -0.7874 -0.4064)
			(stroke
				(width 0.1524)
				(type default)
			)
			(layer "F.SilkS")
		)
		(fp_line
			(start 0.7874 -0.4064)
			(end 0.7874 0.4064)
			(stroke
				(width 0.1524)
				(type default)
			)
			(layer "F.SilkS")
		)
		(fp_line
			(start 0.7874 0.4064)
			(end -0.7874 0.4064)
			(stroke
				(width 0.1524)
				(type default)
			)
			(layer "F.SilkS")
		)
		(fp_line
			(start -0.67945 -0.305054)
			(end -0.12065 -0.305054)
			(stroke
				(width 0.1)
				(type default)
			)
			(layer "F.Fab")
		)
		(fp_line
			(start -0.67945 0.3048)
			(end -0.67945 -0.305054)
			(stroke
				(width 0.1)
				(type default)
			)
			(layer "F.Fab")
		)
		(fp_line
			(start -0.12065 -0.305054)
			(end -0.12065 -0.2794)
			(stroke
				(width 0.1)
				(type default)
			)
			(layer "F.Fab")
		)
		(fp_line
			(start -0.12065 -0.2794)
			(end 0.12065 -0.2794)
			(stroke
				(width 0.1)
				(type default)
			)
			(layer "F.Fab")
		)
		(fp_line
			(start -0.12065 0.2794)
			(end -0.12065 0.3048)
			(stroke
				(width 0.1)
				(type default)
			)
			(layer "F.Fab")
		)
		(fp_line
			(start -0.12065 0.3048)
			(end -0.67945 0.3048)
			(stroke
				(width 0.1)
				(type default)
			)
			(layer "F.Fab")
		)
		(fp_line
			(start 0.120396 0.2794)
			(end -0.12065 0.2794)
			(stroke
				(width 0.1)
				(type default)
			)
			(layer "F.Fab")
		)
		(fp_line
			(start 0.120396 0.3048)
			(end 0.120396 0.2794)
			(stroke
				(width 0.1)
				(type default)
			)
			(layer "F.Fab")
		)
		(fp_line
			(start 0.12065 -0.3048)
			(end 0.67945 -0.3048)
			(stroke
				(width 0.1)
				(type default)
			)
			(layer "F.Fab")
		)
		(fp_line
			(start 0.12065 -0.2794)
			(end 0.12065 -0.3048)
			(stroke
				(width 0.1)
				(type default)
			)
			(layer "F.Fab")
		)
		(fp_line
			(start 0.67945 -0.3048)
			(end 0.67945 0.3048)
			(stroke
				(width 0.1)
				(type default)
			)
			(layer "F.Fab")
		)
		(fp_line
			(start 0.67945 0.3048)
			(end 0.120396 0.3048)
			(stroke
				(width 0.1)
				(type default)
			)
			(layer "F.Fab")
		)
		(pad "1" smd circle
			(at -0.40005 0)
			(size 0 0)
			(layers "F.Cu" "F.Mask" "F.Paste")
			(net "SVID_CLK1_CPU1_R")
		)
		(pad "2" smd circle
			(at 0.40005 0)
			(size 0 0)
			(layers "F.Cu" "F.Mask" "F.Paste")
			(net "SVID_CLK_PVCCD_HV_CPU1_R")
		)
	)
	(footprint ""
		(layer "F.Cu")
		(at 220.190822 -57.851802 180)
		(property "Reference" "R3758"
			(at 0 0 180)
			(layer "F.SilkS")
			(hide yes)
			(effects
				(font
					(size 1.27 1.27)
				)
			)
		)
		(property "Value" ""
			(at 0 0 180)
			(layer "F.Fab")
			(effects
				(font
					(size 1.27 1.27)
				)
			)
		)
		(duplicate_pad_numbers_are_jumpers no)
		(fp_line
			(start 0.7874 0.4064)
			(end -0.7874 0.4064)
			(stroke
				(width 0.1524)
				(type default)
			)
			(layer "F.SilkS")
		)
		(fp_line
			(start 0.7874 -0.4064)
			(end 0.7874 0.4064)
			(stroke
				(width 0.1524)
				(type default)
			)
			(layer "F.SilkS")
		)
		(fp_line
			(start -0.7874 0.4064)
			(end -0.7874 -0.4064)
			(stroke
				(width 0.1524)
				(type default)
			)
			(layer "F.SilkS")
		)
		(fp_line
			(start -0.7874 -0.4064)
			(end 0.7874 -0.4064)
			(stroke
				(width 0.1524)
				(type default)
			)
			(layer "F.SilkS")
		)
		(fp_line
			(start 0.67945 0.3048)
			(end 0.120396 0.3048)
			(stroke
				(width 0.1)
				(type default)
			)
			(layer "F.Fab")
		)
		(fp_line
			(start 0.67945 -0.3048)
			(end 0.67945 0.3048)
			(stroke
				(width 0.1)
				(type default)
			)
			(layer "F.Fab")
		)
		(fp_line
			(start 0.12065 -0.2794)
			(end 0.12065 -0.3048)
			(stroke
				(width 0.1)
				(type default)
			)
			(layer "F.Fab")
		)
		(fp_line
			(start 0.12065 -0.3048)
			(end 0.67945 -0.3048)
			(stroke
				(width 0.1)
				(type default)
			)
			(layer "F.Fab")
		)
		(fp_line
			(start 0.120396 0.3048)
			(end 0.120396 0.2794)
			(stroke
				(width 0.1)
				(type default)
			)
			(layer "F.Fab")
		)
		(fp_line
			(start 0.120396 0.2794)
			(end -0.12065 0.2794)
			(stroke
				(width 0.1)
				(type default)
			)
			(layer "F.Fab")
		)
		(fp_line
			(start -0.12065 0.3048)
			(end -0.67945 0.3048)
			(stroke
				(width 0.1)
				(type default)
			)
			(layer "F.Fab")
		)
		(fp_line
			(start -0.12065 0.2794)
			(end -0.12065 0.3048)
			(stroke
				(width 0.1)
				(type default)
			)
			(layer "F.Fab")
		)
		(fp_line
			(start -0.12065 -0.2794)
			(end 0.12065 -0.2794)
			(stroke
				(width 0.1)
				(type default)
			)
			(layer "F.Fab")
		)
		(fp_line
			(start -0.12065 -0.305054)
			(end -0.12065 -0.2794)
			(stroke
				(width 0.1)
				(type default)
			)
			(layer "F.Fab")
		)
		(fp_line
			(start -0.67945 0.3048)
			(end -0.67945 -0.305054)
			(stroke
				(width 0.1)
				(type default)
			)
			(layer "F.Fab")
		)
		(fp_line
			(start -0.67945 -0.305054)
			(end -0.12065 -0.305054)
			(stroke
				(width 0.1)
				(type default)
			)
			(layer "F.Fab")
		)
		(pad "1" smd circle
			(at -0.40005 0 180)
			(size 0 0)
			(layers "F.Cu" "F.Mask" "F.Paste")
			(net "P3V3_E1S_0_R")
		)
		(pad "2" smd circle
			(at 0.40005 0 180)
			(size 0 0)
			(layers "F.Cu" "F.Mask" "F.Paste")
			(net "VSENSE_P3V3_INA230_2_INP")
		)
	)
	(footprint ""
		(layer "F.Cu")
		(at 157.988 -22.824948 90)
		(property "Reference" "R1752"
			(at 0 0 90)
			(layer "F.SilkS")
			(hide yes)
			(effects
				(font
					(size 1.27 1.27)
				)
			)
		)
		(property "Value" ""
			(at 0 0 90)
			(layer "F.Fab")
			(effects
				(font
					(size 1.27 1.27)
				)
			)
		)
		(duplicate_pad_numbers_are_jumpers no)
		(fp_line
			(start 0.7874 -0.4064)
			(end 0.7874 0.4064)
			(stroke
				(width 0.1524)
				(type default)
			)
			(layer "F.SilkS")
		)
		(fp_line
			(start -0.7874 -0.4064)
			(end 0.7874 -0.4064)
			(stroke
				(width 0.1524)
				(type default)
			)
			(layer "F.SilkS")
		)
		(fp_line
			(start 0.7874 0.4064)
			(end -0.7874 0.4064)
			(stroke
				(width 0.1524)
				(type default)
			)
			(layer "F.SilkS")
		)
		(fp_line
			(start -0.7874 0.4064)
			(end -0.7874 -0.4064)
			(stroke
				(width 0.1524)
				(type default)
			)
			(layer "F.SilkS")
		)
		(fp_line
			(start -0.12065 -0.305054)
			(end -0.12065 -0.2794)
			(stroke
				(width 0.1)
				(type default)
			)
			(layer "F.Fab")
		)
		(fp_line
			(start -0.67945 -0.305054)
			(end -0.12065 -0.305054)
			(stroke
				(width 0.1)
				(type default)
			)
			(layer "F.Fab")
		)
		(fp_line
			(start 0.67945 -0.3048)
			(end 0.67945 0.3048)
			(stroke
				(width 0.1)
				(type default)
			)
			(layer "F.Fab")
		)
		(fp_line
			(start 0.12065 -0.3048)
			(end 0.67945 -0.3048)
			(stroke
				(width 0.1)
				(type default)
			)
			(layer "F.Fab")
		)
		(fp_line
			(start 0.12065 -0.2794)
			(end 0.12065 -0.3048)
			(stroke
				(width 0.1)
				(type default)
			)
			(layer "F.Fab")
		)
		(fp_line
			(start -0.12065 -0.2794)
			(end 0.12065 -0.2794)
			(stroke
				(width 0.1)
				(type default)
			)
			(layer "F.Fab")
		)
		(fp_line
			(start 0.120396 0.2794)
			(end -0.12065 0.2794)
			(stroke
				(width 0.1)
				(type default)
			)
			(layer "F.Fab")
		)
		(fp_line
			(start -0.12065 0.2794)
			(end -0.12065 0.3048)
			(stroke
				(width 0.1)
				(type default)
			)
			(layer "F.Fab")
		)
		(fp_line
			(start 0.67945 0.3048)
			(end 0.120396 0.3048)
			(stroke
				(width 0.1)
				(type default)
			)
			(layer "F.Fab")
		)
		(fp_line
			(start 0.120396 0.3048)
			(end 0.120396 0.2794)
			(stroke
				(width 0.1)
				(type default)
			)
			(layer "F.Fab")
		)
		(fp_line
			(start -0.12065 0.3048)
			(end -0.67945 0.3048)
			(stroke
				(width 0.1)
				(type default)
			)
			(layer "F.Fab")
		)
		(fp_line
			(start -0.67945 0.3048)
			(end -0.67945 -0.305054)
			(stroke
				(width 0.1)
				(type default)
			)
			(layer "F.Fab")
		)
		(pad "1" smd circle
			(at -0.40005 0 90)
			(size 0 0)
			(layers "F.Cu" "F.Mask" "F.Paste")
			(net "SGPIO_CLK_0")
		)
		(pad "2" smd circle
			(at 0.40005 0 90)
			(size 0 0)
			(layers "F.Cu" "F.Mask" "F.Paste")
			(net "SGPIO_DEBUG_PLD_CLK")
		)
	)
	(footprint ""
		(layer "F.Cu")
		(at 355.247448 -249.320304 -90)
		(property "Reference" "C967"
			(at 0 0 270)
			(layer "F.SilkS")
			(hide yes)
			(effects
				(font
					(size 1.27 1.27)
				)
			)
		)
		(property "Value" ""
			(at 0 0 270)
			(layer "F.Fab")
			(effects
				(font
					(size 1.27 1.27)
				)
			)
		)
		(duplicate_pad_numbers_are_jumpers no)
		(fp_line
			(start -0.7874 0.4064)
			(end -0.7874 -0.4064)
			(stroke
				(width 0.1524)
				(type default)
			)
			(layer "F.SilkS")
		)
		(fp_line
			(start 0.7874 0.4064)
			(end -0.7874 0.4064)
			(stroke
				(width 0.1524)
				(type default)
			)
			(layer "F.SilkS")
		)
		(fp_line
			(start -0.7874 -0.4064)
			(end 0.7874 -0.4064)
			(stroke
				(width 0.1524)
				(type default)
			)
			(layer "F.SilkS")
		)
		(fp_line
			(start 0.7874 -0.4064)
			(end 0.7874 0.4064)
			(stroke
				(width 0.1524)
				(type default)
			)
			(layer "F.SilkS")
		)
		(fp_line
			(start -0.67945 0.3048)
			(end -0.67945 -0.305054)
			(stroke
				(width 0.1)
				(type default)
			)
			(layer "F.Fab")
		)
		(fp_line
			(start -0.12065 0.3048)
			(end -0.67945 0.3048)
			(stroke
				(width 0.1)
				(type default)
			)
			(layer "F.Fab")
		)
		(fp_line
			(start 0.120396 0.3048)
			(end 0.120396 0.2794)
			(stroke
				(width 0.1)
				(type default)
			)
			(layer "F.Fab")
		)
		(fp_line
			(start 0.67945 0.3048)
			(end 0.120396 0.3048)
			(stroke
				(width 0.1)
				(type default)
			)
			(layer "F.Fab")
		)
		(fp_line
			(start -0.12065 0.2794)
			(end -0.12065 0.3048)
			(stroke
				(width 0.1)
				(type default)
			)
			(layer "F.Fab")
		)
		(fp_line
			(start 0.120396 0.2794)
			(end -0.12065 0.2794)
			(stroke
				(width 0.1)
				(type default)
			)
			(layer "F.Fab")
		)
		(fp_line
			(start -0.12065 -0.2794)
			(end 0.12065 -0.2794)
			(stroke
				(width 0.1)
				(type default)
			)
			(layer "F.Fab")
		)
		(fp_line
			(start 0.12065 -0.2794)
			(end 0.12065 -0.3048)
			(stroke
				(width 0.1)
				(type default)
			)
			(layer "F.Fab")
		)
		(fp_line
			(start 0.12065 -0.3048)
			(end 0.67945 -0.3048)
			(stroke
				(width 0.1)
				(type default)
			)
			(layer "F.Fab")
		)
		(fp_line
			(start 0.67945 -0.3048)
			(end 0.67945 0.3048)
			(stroke
				(width 0.1)
				(type default)
			)
			(layer "F.Fab")
		)
		(fp_line
			(start -0.67945 -0.305054)
			(end -0.12065 -0.305054)
			(stroke
				(width 0.1)
				(type default)
			)
			(layer "F.Fab")
		)
		(fp_line
			(start -0.12065 -0.305054)
			(end -0.12065 -0.2794)
			(stroke
				(width 0.1)
				(type default)
			)
			(layer "F.Fab")
		)
		(pad "1" smd circle
			(at -0.40005 0 270)
			(size 0 0)
			(layers "F.Cu" "F.Mask" "F.Paste")
			(net "PVCCIN_CPU0")
		)
		(pad "2" smd circle
			(at 0.40005 0 270)
			(size 0 0)
			(layers "F.Cu" "F.Mask" "F.Paste")
			(net "GND")
		)
	)
	(footprint ""
		(layer "F.Cu")
		(at 250.733306 -108.192824 90)
		(property "Reference" "R1010"
			(at 0 0 90)
			(layer "F.SilkS")
			(hide yes)
			(effects
				(font
					(size 1.27 1.27)
				)
			)
		)
		(property "Value" ""
			(at 0 0 90)
			(layer "F.Fab")
			(effects
				(font
					(size 1.27 1.27)
				)
			)
		)
		(duplicate_pad_numbers_are_jumpers no)
		(fp_line
			(start 0.7874 -0.4064)
			(end 0.7874 0.4064)
			(stroke
				(width 0.1524)
				(type default)
			)
			(layer "F.SilkS")
		)
		(fp_line
			(start -0.7874 -0.4064)
			(end 0.7874 -0.4064)
			(stroke
				(width 0.1524)
				(type default)
			)
			(layer "F.SilkS")
		)
		(fp_line
			(start 0.7874 0.4064)
			(end -0.7874 0.4064)
			(stroke
				(width 0.1524)
				(type default)
			)
			(layer "F.SilkS")
		)
		(fp_line
			(start -0.7874 0.4064)
			(end -0.7874 -0.4064)
			(stroke
				(width 0.1524)
				(type default)
			)
			(layer "F.SilkS")
		)
		(fp_line
			(start -0.12065 -0.305054)
			(end -0.12065 -0.2794)
			(stroke
				(width 0.1)
				(type default)
			)
			(layer "F.Fab")
		)
		(fp_line
			(start -0.67945 -0.305054)
			(end -0.12065 -0.305054)
			(stroke
				(width 0.1)
				(type default)
			)
			(layer "F.Fab")
		)
		(fp_line
			(start 0.67945 -0.3048)
			(end 0.67945 0.3048)
			(stroke
				(width 0.1)
				(type default)
			)
			(layer "F.Fab")
		)
		(fp_line
			(start 0.12065 -0.3048)
			(end 0.67945 -0.3048)
			(stroke
				(width 0.1)
				(type default)
			)
			(layer "F.Fab")
		)
		(fp_line
			(start 0.12065 -0.2794)
			(end 0.12065 -0.3048)
			(stroke
				(width 0.1)
				(type default)
			)
			(layer "F.Fab")
		)
		(fp_line
			(start -0.12065 -0.2794)
			(end 0.12065 -0.2794)
			(stroke
				(width 0.1)
				(type default)
			)
			(layer "F.Fab")
		)
		(fp_line
			(start 0.120396 0.2794)
			(end -0.12065 0.2794)
			(stroke
				(width 0.1)
				(type default)
			)
			(layer "F.Fab")
		)
		(fp_line
			(start -0.12065 0.2794)
			(end -0.12065 0.3048)
			(stroke
				(width 0.1)
				(type default)
			)
			(layer "F.Fab")
		)
		(fp_line
			(start 0.67945 0.3048)
			(end 0.120396 0.3048)
			(stroke
				(width 0.1)
				(type default)
			)
			(layer "F.Fab")
		)
		(fp_line
			(start 0.120396 0.3048)
			(end 0.120396 0.2794)
			(stroke
				(width 0.1)
				(type default)
			)
			(layer "F.Fab")
		)
		(fp_line
			(start -0.12065 0.3048)
			(end -0.67945 0.3048)
			(stroke
				(width 0.1)
				(type default)
			)
			(layer "F.Fab")
		)
		(fp_line
			(start -0.67945 0.3048)
			(end -0.67945 -0.305054)
			(stroke
				(width 0.1)
				(type default)
			)
			(layer "F.Fab")
		)
		(pad "1" smd circle
			(at -0.40005 0 90)
			(size 0 0)
			(layers "F.Cu" "F.Mask" "F.Paste")
			(net "CLK_25M_CK440_ISCLK_REF_DP")
		)
		(pad "2" smd circle
			(at 0.40005 0 90)
			(size 0 0)
			(layers "F.Cu" "F.Mask" "F.Paste")
			(net "CLK_25M_PCH_REF_NS_DP")
		)
	)
)
